FILE_TYPE = CONNECTIVITY;
{Allegro Design Entry HDL 17.4-2019 S026 (4007227) 1/17/2022}
"PAGE_NUMBER" = 195;
0"NC";
1"GND\g";
2"GND\g";
3"GND\g";
4"GND\g";
5"GND\g";
6"GND\g";
7"GND\g";
8"GND\g";
9"GND\g";
10"GND\g";
11"GND\g";
12"SW_PVDDCR_CPU1_P1_SW6";
13"PVDDCR_CPU1_P1_VOS6";
14"GND\g";
15"SW_P12V_AUX_PVDDCR_CPU1_P1_FLT\g";
16"PVDDCR_CPU1_P1_VOS5";
17"SW_PVDDCR_CPU1_P1_SW5";
18"SW_PVDDCR_CPU1_P1_BOOTR5";
19"GND\g";
20"SW_PVDDCR_CPU1_P1_BOOT5_R";
21"SW_PVDDCR_CPU1_P1_BOOT5";
22"SW_PVDDCR_CPU1_P1_BOOT6";
23"SW_PVDDCR_CPU1_P1_BOOT6_R";
24"SW_PVDDCR_CPU1_P1_BOOTR6";
25"IND_CPU1_P1_CPL0";
26"PVDDCR_CPU1_P1_PVCC\g";
27"GND\g";
28"GND\g";
29"PVDDCR_CPU1_P1_PVCC\g";
30"SW_P12V_AUX_PVDDCR_CPU1_P1_FLT\g";
31"GND\g";
32"PVDDCR_CPU1_P1\g";
33"GND\g";
34"PVDDCR_CPU1_P1\g";
35"NC_PVDDCR_CPU1_P1_GL1_5";
36"IND_CPU1_P1_CPL5";
37"IND_CPU1_P1_CPL6";
38"SW_PVDDCR_CPU1_P1_SW5_RC";
39"IND_CPU1_P1_CPL6";
40"SW_PVDDCR_CPU1_P1_SW6_RC";
41"NC_PVDDCR_CPU1_P1_GL2_5";
42"NC_PVDDCR_CPU1_P1_GL2_6";
43"NC_PVDDCR_CPU1_P1_GL1_6";
44"PVDDCR_CPU1_P1_VCC5";
45"NC_PVDDCR_CPU1_P1_DNC5";
46"PVDDCR_CPU1_P1_VCCS"CDS_PHYS_NET_NAME"PVDDCR_CPU1_P1_VCCS";
47"PVDDCR_CPU1_P1_IMON5";
48"PVDDCR_CPU1_P1_LSET5";
49"PVDDCR_CPU1_P1_VCC6";
50"NC_PVDDCR_CPU1_P1_DNC6";
51"PVDDCR_CPU1_P1_PWM6";
52"PVDDCR_CPU1_P1_IMON6";
53"PVDDCR_CPU1_P1_PWM5";
54"PVDDCR_CPU1_P1_TEMP0";
55"PVDDCR_CPU1_P1_TEMP0";
56"PVDDCR_CPU1_P1_VCCS"CDS_PHYS_NET_NAME"PVDDCR_CPU1_P1_VCCS";
57"PVDDCR_CPU1_P1_LSET6";
%"Q_CAP"
"1","(775,1850)","0","pure_quanta","I1";
;
LOCATION"PC136_6"
$SEC"1"
CDS_SEC"1"
MATERIAL"X7R"
TOLERANCE"10%"
VALUE"0.1UF"
VOLTAGE"25V"
PACK_TYPE"0402"
CDS_LIB"pure_quanta"
PART_NUMBER"CH4104K1B00";
"B"
$PN"2"3;
"A"
$PN"1"56;
%"Q_CAP"
"1","(725,4475)","0","pure_quanta","I10";
;
LOCATION"PC422_5"
$SEC"1"
CDS_SEC"1"
MATERIAL"X7R"
TOLERANCE"10%"
VALUE"0.1UF"
VOLTAGE"25V"
PACK_TYPE"0402"
CDS_LIB"pure_quanta"
PART_NUMBER"CH4104K1B00";
"B"
$PN"2"11;
"A"
$PN"1"46;
%"UNIVERSAL_GND"
"1","(1725,2450)","0","pure_quanta_power","I11";
;
CDS_LIB"pure_quanta_power"
HDL_POWER"GND";
"A"1;
%"Q_CAP"
"1","(1725,2650)","0","pure_quanta","I12";
;
LOCATION"PC138"
$SEC"1"
CDS_SEC"1"
MATERIAL"X6S"
TOLERANCE"10%"
VALUE"2.2UF"
VOLTAGE"10V"
PACK_TYPE"C0402"
CDS_LIB"pure_quanta"
PART_NUMBER"CH5222KEB01";
"B"
$PN"2"1;
"A"
$PN"1"49;
%"Q_RES"
"2","(1725,3200)","0","pure_quanta","I13";
;
LOCATION"PR427"
$SEC"1"
CDS_SEC"1"
PACK_TYPE"0402LF"
VALUE"2.2"
TOLERANCE"1%"
MATERIAL"CHIP"
WATTAGE"1/16W"
CDS_LIB"pure_quanta"
PART_NUMBER"CS-2202FB01";
"A"
$PN"1"26;
"B"
$PN"2"49;
%"UNIVERSAL_GND"
"1","(1225,4125)","0","pure_quanta_power","I14";
;
CDS_LIB"pure_quanta_power"
HDL_POWER"GND";
"A"2;
%"Q_RES"
"2","(1225,4350)","2","pure_quanta","I15";
;
LOCATION"PR270"
$SEC"1"
CDS_SEC"1"
WATTAGE"1/16W"
MATERIAL"EMPTY"
TOLERANCE"1%"
VALUE"8.87K"
PACK_TYPE"0402LF"
CDS_LIB"pure_quanta"
PART_NUMBER"CS28872FB01";
"A"
$PN"1"48;
"B"
$PN"2"2;
%"VCC_CORE"
"1","(1725,3600)","0","pure_quanta_power","I16";
;
HDL_POWER"PVDDCR_CPU1_P1_PVCC"
CDS_LIB"pure_quanta_power";
"A"26;
%"ISL99390FRZTR5935"
"1","(3200,2225)","0","pure_quanta","I19";
;
LOCATION"PU33"
$SEC"1"
CDS_SEC"1"
VALUE"ISL99390FRZ-TR5935"
PART_TYPE"SMLF"
MATERIAL"IC"
NEEDS_NO_SIZE"TRUE"
CDS_LMAN_SYM_OUTLINE"-300,700,250,-650"
CDS_LIB"pure_quanta"
PART_NUMBER"AL099390004";
"PGND2"
$PN"7_9-20_24"27;
"GL2"
$PN"41"42;
"GL1"
$PN"6"43;
"DNC"
$PN"31"50;
"EN"
$PN"35"49;
"PGND3"
$PN"40"27;
"VOS"
$PN"1"13;
"VIN2"
$PN"30"15;
"PGND1"
$PN"5"27;
"SW"
$PN"10_19"12;
"LSET"
$PN"37"57;
"IOUT"
$PN"38"52;
"TOUT_FLT"
$PN"36"55;
"PVCC"
$PN"4"26;
"PHASE"
$PN"32"24;
"VIN1"
$PN"25_29"15;
"BOOT"
$PN"33"22;
"AGND"
$PN"2"27;
"VCC"
$PN"3"49;
"REFIN"
$PN"39"56;
"PWM"
$PN"34"51;
%"UNIVERSAL_GND"
"1","(775,1650)","0","pure_quanta_power","I2";
;
CDS_LIB"pure_quanta_power"
HDL_POWER"GND";
"A"3;
%"UNIVERSAL_GND"
"1","(3850,1500)","0","pure_quanta_power","I20";
;
CDS_LIB"pure_quanta_power"
HDL_POWER"GND";
"A"27;
%"UNIVERSAL_GND"
"1","(2075,2950)","0","pure_quanta_power","I21";
;
CDS_LIB"pure_quanta_power"
HDL_POWER"GND";
"A"4;
%"Q_CAP"
"1","(2075,3225)","0","pure_quanta","I22";
;
LOCATION"PC139_C1P1_6"
$SEC"1"
CDS_SEC"1"
MATERIAL"X6S"
TOLERANCE"10%"
VALUE"2.2UF"
VOLTAGE"10V"
PACK_TYPE"C0402"
CDS_LIB"pure_quanta"
PART_NUMBER"CH5222KEB01";
"B"
$PN"2"4;
"A"
$PN"1"26;
%"UNIVERSAL_GND"
"1","(3800,4125)","0","pure_quanta_power","I23";
;
CDS_LIB"pure_quanta_power"
HDL_POWER"GND";
"A"28;
%"UNIVERSAL_GND"
"1","(1675,5075)","0","pure_quanta_power","I26";
;
CDS_LIB"pure_quanta_power"
HDL_POWER"GND";
"A"5;
%"Q_CAP"
"1","(1675,5275)","0","pure_quanta","I27";
;
LOCATION"PC421"
$SEC"1"
CDS_SEC"1"
MATERIAL"X6S"
TOLERANCE"10%"
VALUE"2.2UF"
VOLTAGE"10V"
PACK_TYPE"C0402"
CDS_LIB"pure_quanta"
PART_NUMBER"CH5222KEB01";
"B"
$PN"2"5;
"A"
$PN"1"44;
%"Q_RES"
"2","(1675,5825)","0","pure_quanta","I28";
;
LOCATION"PR271"
$SEC"1"
CDS_SEC"1"
PACK_TYPE"0402LF"
VALUE"2.2"
TOLERANCE"1%"
MATERIAL"CHIP"
WATTAGE"1/16W"
CDS_LIB"pure_quanta"
PART_NUMBER"CS-2202FB01";
"A"
$PN"1"29;
"B"
$PN"2"44;
%"VCC_CORE"
"1","(1675,6225)","0","pure_quanta_power","I29";
;
HDL_POWER"PVDDCR_CPU1_P1_PVCC"
CDS_LIB"pure_quanta_power";
"A"29;
%"UNIVERSAL_GND"
"1","(1275,1500)","0","pure_quanta_power","I3";
;
CDS_LIB"pure_quanta_power"
HDL_POWER"GND";
"A"6;
%"UNIVERSAL_GND"
"1","(2025,5575)","0","pure_quanta_power","I30";
;
CDS_LIB"pure_quanta_power"
HDL_POWER"GND";
"A"7;
%"Q_CAP"
"1","(2025,5850)","0","pure_quanta","I31";
;
LOCATION"PC423_C1P1_5"
$SEC"1"
CDS_SEC"1"
MATERIAL"X6S"
TOLERANCE"10%"
VALUE"2.2UF"
VOLTAGE"10V"
PACK_TYPE"C0402"
CDS_LIB"pure_quanta"
PART_NUMBER"CH5222KEB01";
"B"
$PN"2"7;
"A"
$PN"1"29;
%"UNIVERSAL_GND"
"1","(4725,1275)","0","pure_quanta_power","I32";
;
CDS_LIB"pure_quanta_power"
HDL_POWER"GND";
"A"8;
%"Q_RES"
"2","(4725,1500)","0","pure_quanta","I33";
;
LOCATION"PR518"
$SEC"1"
CDS_SEC"1"
PACK_TYPE"0402LF"
MATERIAL"EMPTY"
WATTAGE"1/8W"
TOLERANCE"1%"
VALUE"1.5"
CDS_LIB"pure_quanta"
PART_NUMBER"CS-1504FB00";
"A"
$PN"1"40;
"B"
$PN"2"8;
%"Q_CAP"
"1","(4725,2025)","0","pure_quanta","I34";
;
LOCATION"PC208"
$SEC"1"
CDS_SEC"1"
PACK_TYPE"C0402"
VOLTAGE"50V"
TOLERANCE"10%"
MATERIAL"EMPTY"
VALUE"560PF"
CDS_LIB"pure_quanta"
PART_NUMBER"CH1566K1B09";
"B"
$PN"2"40;
"A"
$PN"1"12;
%"Q_RES"
"1","(5750,1075)","0","pure_quanta","I35";
;
LOCATION"PR429"
$SEC"1"
CDS_SEC"1"
VALUE"0"
PACK_TYPE"0402LF"
TOLERANCE"5%"
MATERIAL"CHIP"
WATTAGE"1/16W"
CDS_LIB"pure_quanta"
PART_NUMBER"CS00002JB13";
"B"
$PN"2"32;
"A"
$PN"1"13;
%"UNIVERSAL_GND"
"1","(5375,1875)","0","pure_quanta_power","I36";
;
CDS_LIB"pure_quanta_power"
HDL_POWER"GND";
"A"9;
%"Q_INDUCTOR"
"1","(5575,2000)","2","pure_quanta","I37";
;
LOCATION"PL39"
$SEC"1"
CDS_SEC"1"
PACK_TYPE"SMLF"
MATERIAL"IND"
VALUE"120NH/69A"
NEEDS_NO_SIZE"TRUE"
CDS_LIB"pure_quanta"
PART_NUMBER"CV+12^0EZ03";
"1"
$PN"1"25;
"2"
$PN"2"9;
%"Q_CAP"
"1","(4050,3125)","0","pure_quanta","I38";
;
LOCATION"PC141_6"
$SEC"1"
CDS_SEC"1"
VOLTAGE"25V"
TOLERANCE"10%"
VALUE"0.1UF"
MATERIAL"X7R"
PACK_TYPE"0402"
CDS_LIB"pure_quanta"
PART_NUMBER"CH4104K1B00";
"B"
$PN"2"14;
"A"
$PN"1"15;
%"Q_RES"
"1","(4550,2575)","0","pure_quanta","I39";
;
LOCATION"PR428"
$SEC"1"
CDS_SEC"1"
TOLERANCE"1%"
WATTAGE"1/16W"
PACK_TYPE"0402LF"
MATERIAL"CHIP"
VALUE"5.6"
CDS_LIB"pure_quanta"
PART_NUMBER"CS-5602FB01";
"B"
$PN"2"23;
"A"
$PN"1"22;
%"Q_RES"
"2","(1275,1725)","2","pure_quanta","I4";
;
LOCATION"PR426"
$SEC"1"
CDS_SEC"1"
WATTAGE"1/16W"
MATERIAL"EMPTY"
TOLERANCE"1%"
VALUE"8.87K"
PACK_TYPE"0402LF"
CDS_LIB"pure_quanta"
PART_NUMBER"CS28872FB01";
"A"
$PN"1"57;
"B"
$PN"2"6;
%"Q_CAP"
"1","(4475,3125)","0","pure_quanta","I40";
;
LOCATION"PC140_6"
$SEC"1"
CDS_SEC"1"
VALUE"1UF"
MATERIAL"X6S"
TOLERANCE"10%"
VOLTAGE"25V"
PACK_TYPE"C0402"
CDS_LIB"pure_quanta"
PART_NUMBER"CH5104KEB02";
"B"
$PN"2"14;
"A"
$PN"1"15;
%"Q_CAP"
"1","(4875,3125)","0","pure_quanta","I41";
;
LOCATION"PC144_6"
$SEC"1"
CDS_SEC"1"
PACK_TYPE"C0805"
MATERIAL"X6S"
VALUE"22UF"
VOLTAGE"16V"
TOLERANCE"20%"
CDS_LIB"pure_quanta"
PART_NUMBER"CH6223MEA01";
"B"
$PN"2"14;
"A"
$PN"1"15;
%"UNIVERSAL_GND"
"1","(4650,3950)","0","pure_quanta_power","I42";
;
CDS_LIB"pure_quanta_power"
HDL_POWER"GND";
"A"10;
%"Q_RES"
"2","(4650,4175)","0","pure_quanta","I43";
;
LOCATION"PR517"
$SEC"1"
CDS_SEC"1"
WATTAGE"1/8W"
MATERIAL"EMPTY"
TOLERANCE"1%"
VALUE"1.5"
PACK_TYPE"0402LF"
CDS_LIB"pure_quanta"
PART_NUMBER"CS-1504FB00";
"A"
$PN"1"38;
"B"
$PN"2"10;
%"Q_CAP"
"1","(5275,3125)","0","pure_quanta","I44";
;
LOCATION"PC145_6"
$SEC"1"
CDS_SEC"1"
PACK_TYPE"C0805"
MATERIAL"X6S"
VALUE"22UF"
VOLTAGE"16V"
TOLERANCE"20%"
CDS_LIB"pure_quanta"
PART_NUMBER"CH6223MEA01";
"B"
$PN"2"14;
"A"
$PN"1"15;
%"Q_CAP"
"1","(5450,2450)","0","pure_quanta","I45";
;
LOCATION"PC146"
$SEC"1"
CDS_SEC"1"
MATERIAL"X7R"
TOLERANCE"10%"
VALUE"0.22UF"
VOLTAGE"16V"
PACK_TYPE"0402"
CDS_LIB"pure_quanta"
PART_NUMBER"CH4223K1B00";
"B"
$PN"2"24;
"A"
$PN"1"23;
%"UNIVERSAL_GND"
"1","(5650,2775)","0","pure_quanta_power","I46";
;
CDS_LIB"pure_quanta_power"
HDL_POWER"GND";
"A"14;
%"Q_CAP"
"1","(5650,3125)","0","pure_quanta","I47";
;
LOCATION"PC147_6"
$SEC"1"
CDS_SEC"1"
PACK_TYPE"C0805"
MATERIAL"X6S"
VALUE"22UF"
VOLTAGE"16V"
TOLERANCE"20%"
CDS_LIB"pure_quanta"
PART_NUMBER"CH6223MEA01";
"B"
$PN"2"14;
"A"
$PN"1"15;
%"VCC_CORE"
"1","(5650,3475)","0","pure_quanta_power","I48";
;
HDL_POWER"SW_P12V_AUX_PVDDCR_CPU1_P1_FLT"
CDS_LIB"pure_quanta_power";
"A"15;
%"Q_RES"
"1","(5575,3800)","0","pure_quanta","I49";
;
LOCATION"PR273"
$SEC"1"
CDS_SEC"1"
TOLERANCE"5%"
PACK_TYPE"0402LF"
VALUE"0"
MATERIAL"CHIP"
WATTAGE"1/16W"
CDS_LIB"pure_quanta"
PART_NUMBER"CS00002JB13";
"B"
$PN"2"34;
"A"
$PN"1"16;
%"Q_INDUCTOR4P_14"
"1","(6650,2100)","0","pure_quanta","I50";
;
LOCATION"PL69"
$SEC"1"
CDS_SEC"1"
MATERIAL"IND"
VALUE"150NH"
PART_TYPE"SMLF"
CDS_LIB"pure_quanta"
NEEDS_NO_SIZE"TRUE"
PART_NUMBER"CV+15^0TZ04";
"1"
$PN"1"12;
"4"
$PN"4"32;
"3"
$PN"3"39;
"2"
$PN"2"25;
%"Q_RES"
"1","(4500,5200)","0","pure_quanta","I52";
;
LOCATION"PR272"
$SEC"1"
CDS_SEC"1"
WATTAGE"1/16W"
TOLERANCE"1%"
MATERIAL"CHIP"
PACK_TYPE"0402LF"
VALUE"5.6"
CDS_LIB"pure_quanta"
PART_NUMBER"CS-5602FB01";
"B"
$PN"2"20;
"A"
$PN"1"21;
%"Q_CAP"
"1","(4650,4650)","0","pure_quanta","I53";
;
LOCATION"PC207"
$SEC"1"
CDS_SEC"1"
VALUE"560PF"
VOLTAGE"50V"
MATERIAL"EMPTY"
TOLERANCE"10%"
PACK_TYPE"C0402"
CDS_LIB"pure_quanta"
PART_NUMBER"CH1566K1B09";
"B"
$PN"2"38;
"A"
$PN"1"17;
%"Q_CAP"
"1","(4000,5750)","0","pure_quanta","I54";
;
LOCATION"PC425_5"
$SEC"1"
CDS_SEC"1"
VALUE"0.1UF"
TOLERANCE"10%"
VOLTAGE"25V"
MATERIAL"X7R"
PACK_TYPE"0402"
CDS_LIB"pure_quanta"
PART_NUMBER"CH4104K1B00";
"B"
$PN"2"19;
"A"
$PN"1"30;
%"Q_CAP"
"1","(4425,5750)","0","pure_quanta","I55";
;
LOCATION"PC424_5"
$SEC"1"
CDS_SEC"1"
TOLERANCE"10%"
VALUE"1UF"
VOLTAGE"25V"
MATERIAL"X6S"
PACK_TYPE"C0402"
CDS_LIB"pure_quanta"
PART_NUMBER"CH5104KEB02";
"B"
$PN"2"19;
"A"
$PN"1"30;
%"Q_CAP"
"1","(4825,5750)","0","pure_quanta","I56";
;
LOCATION"PC426_5"
$SEC"1"
CDS_SEC"1"
PACK_TYPE"C0805"
MATERIAL"X6S"
VOLTAGE"16V"
TOLERANCE"20%"
VALUE"22UF"
CDS_LIB"pure_quanta"
PART_NUMBER"CH6223MEA01";
"B"
$PN"2"19;
"A"
$PN"1"30;
%"Q_CAP"
"1","(5400,5075)","0","pure_quanta","I57";
;
LOCATION"PC428"
$SEC"1"
CDS_SEC"1"
VOLTAGE"16V"
PACK_TYPE"0402"
MATERIAL"X7R"
TOLERANCE"10%"
VALUE"0.22UF"
CDS_LIB"pure_quanta"
PART_NUMBER"CH4223K1B00";
"B"
$PN"2"18;
"A"
$PN"1"20;
%"UNIVERSAL_GND"
"1","(5600,5400)","0","pure_quanta_power","I59";
;
CDS_LIB"pure_quanta_power"
HDL_POWER"GND";
"A"19;
%"Q_CAP"
"1","(5225,5750)","0","pure_quanta","I60";
;
LOCATION"PC427_5"
$SEC"1"
CDS_SEC"1"
VALUE"22UF"
VOLTAGE"16V"
TOLERANCE"20%"
MATERIAL"X6S"
PACK_TYPE"C0805"
CDS_LIB"pure_quanta"
PART_NUMBER"CH6223MEA01";
"B"
$PN"2"19;
"A"
$PN"1"30;
%"Q_CAP"
"1","(5600,5750)","0","pure_quanta","I61";
;
LOCATION"PC429_5"
$SEC"1"
CDS_SEC"1"
PACK_TYPE"C0805"
MATERIAL"X6S"
VALUE"22UF"
VOLTAGE"16V"
TOLERANCE"20%"
CDS_LIB"pure_quanta"
PART_NUMBER"CH6223MEA01";
"B"
$PN"2"19;
"A"
$PN"1"30;
%"VCC_CORE"
"1","(5600,6100)","0","pure_quanta_power","I62";
;
HDL_POWER"SW_P12V_AUX_PVDDCR_CPU1_P1_FLT"
CDS_LIB"pure_quanta_power";
"A"30;
%"Q_INDUCTOR4P_14"
"1","(6600,4725)","0","pure_quanta","I63";
;
LOCATION"PL45"
$SEC"1"
CDS_SEC"1"
PART_TYPE"SMLF"
MATERIAL"IND"
VALUE"150NH"
NEEDS_NO_SIZE"TRUE"
CDS_LIB"pure_quanta"
PART_NUMBER"CV+15^0TZ04";
"1"
$PN"1"17;
"4"
$PN"4"34;
"3"
$PN"3"36;
"2"
$PN"2"37;
%"Q_CAP"
"1","(8150,2025)","0","pure_quanta","I65";
;
LOCATION"PC148_6"
$SEC"1"
CDS_SEC"1"
VOLTAGE"4V"
VALUE"22UF"
TOLERANCE"20%"
MATERIAL"X6S"
PACK_TYPE"C0805"
CDS_LIB"pure_quanta"
PART_NUMBER"CH622KMEA03";
"B"
$PN"2"31;
"A"
$PN"1"32;
%"UNIVERSAL_GND"
"1","(8575,1675)","0","pure_quanta_power","I66";
;
CDS_LIB"pure_quanta_power"
HDL_POWER"GND";
"A"31;
%"Q_CAP"
"1","(8575,2025)","0","pure_quanta","I67";
;
LOCATION"PC149_6"
$SEC"1"
CDS_SEC"1"
VOLTAGE"4V"
VALUE"22UF"
TOLERANCE"20%"
MATERIAL"X6S"
PACK_TYPE"C0805"
CDS_LIB"pure_quanta"
PART_NUMBER"CH622KMEA03";
"B"
$PN"2"31;
"A"
$PN"1"32;
%"VCC_CORE"
"1","(8575,2375)","0","pure_quanta_power","I68";
;
HDL_POWER"PVDDCR_CPU1_P1"
CDS_LIB"pure_quanta_power";
"A"32;
%"UNIVERSAL_GND"
"1","(8525,4300)","0","pure_quanta_power","I69";
;
CDS_LIB"pure_quanta_power"
HDL_POWER"GND";
"A"33;
%"Q_CAP"
"1","(8100,4650)","0","pure_quanta","I70";
;
LOCATION"PC430_5"
$SEC"1"
CDS_SEC"1"
MATERIAL"X6S"
TOLERANCE"20%"
VALUE"22UF"
VOLTAGE"4V"
PACK_TYPE"C0805"
CDS_LIB"pure_quanta"
PART_NUMBER"CH622KMEA03";
"B"
$PN"2"33;
"A"
$PN"1"34;
%"Q_CAP"
"1","(8525,4650)","0","pure_quanta","I71";
;
LOCATION"PC431_5"
$SEC"1"
CDS_SEC"1"
VOLTAGE"4V"
VALUE"22UF"
TOLERANCE"20%"
MATERIAL"X6S"
PACK_TYPE"C0805"
CDS_LIB"pure_quanta"
PART_NUMBER"CH622KMEA03";
"B"
$PN"2"33;
"A"
$PN"1"34;
%"VCC_CORE"
"1","(8525,5000)","0","pure_quanta_power","I72";
;
HDL_POWER"PVDDCR_CPU1_P1"
CDS_LIB"pure_quanta_power";
"A"34;
%"ISL99390FRZTR5935"
"1","(3150,4850)","0","pure_quanta","I73";
;
LOCATION"PU38"
$SEC"1"
CDS_SEC"1"
MATERIAL"IC"
VALUE"ISL99390FRZ-TR5935"
PART_TYPE"SMLF"
NEEDS_NO_SIZE"TRUE"
CDS_LMAN_SYM_OUTLINE"-300,700,250,-650"
CDS_LIB"pure_quanta"
PART_NUMBER"AL099390004";
"PGND2"
$PN"7_9-20_24"28;
"GL2"
$PN"41"41;
"GL1"
$PN"6"35;
"DNC"
$PN"31"45;
"EN"
$PN"35"44;
"PGND3"
$PN"40"28;
"VOS"
$PN"1"16;
"VIN2"
$PN"30"30;
"PGND1"
$PN"5"28;
"SW"
$PN"10_19"17;
"LSET"
$PN"37"48;
"IOUT"
$PN"38"47;
"TOUT_FLT"
$PN"36"54;
"PVCC"
$PN"4"29;
"PHASE"
$PN"32"18;
"VIN1"
$PN"25_29"30;
"BOOT"
$PN"33"21;
"AGND"
$PN"2"28;
"VCC"
$PN"3"44;
"REFIN"
$PN"39"46;
"PWM"
$PN"34"53;
%"UNIVERSAL_GND"
"1","(725,4275)","0","pure_quanta_power","I9";
;
CDS_LIB"pure_quanta_power"
HDL_POWER"GND";
"A"11;
END.
